# T6G (Grand Teton) — schematic netlist excerpt (pin names and nets, part order shuffled) for the footprints in the layout excerpt that follows; sources: Cadence DE-HDL packaged netlist, KiCad conversion of 04192023_DAF0TMB3IC0_F0TG_MB_C_brd_V02_OCP.brd

R6069  Q_RES  0 5% CHIP  pkg 0402LF  page 151 : A = JTAG_SCM_TDI_R ; B = JTAG_SCM_TDO
R380  Q_RES  15 1% CHIP  pkg 0402LF  page 15 : A = M_F_CPU0_ALERT_N ; B = M_F_CPU0_ALERT_R_N

(kicad_pcb
	(version 20260206)
	(generator "pcbnew")
	(generator_version "10.0")
	(general
		(thickness 1.6)
		(legacy_teardrops no)
	)
	(paper "A4")
	(title_block
		(title "04192023_DAF0TMB3IC0_F0TG_MB_C_brd_V02_OCP.brd")
		(comment 1 "Grand Teton / footprints 6259-6260 of 8354")
	)
	(layers
		(0 "F.Cu" signal "TOP")
		(4 "In1.Cu" signal "GND")
		(6 "In2.Cu" signal "IN1")
		(8 "In3.Cu" signal "GND1")
		(10 "In4.Cu" signal "IN2")
		(12 "In5.Cu" signal "GND2")
		(14 "In6.Cu" signal "IN3")
		(16 "In7.Cu" signal "GND3")
		(18 "In8.Cu" signal "VCC")
		(20 "In9.Cu" signal "VCC1")
		(22 "In10.Cu" signal "GND4")
		(24 "In11.Cu" signal "IN4")
		(26 "In12.Cu" signal "GND5")
		(28 "In13.Cu" signal "IN5")
		(30 "In14.Cu" signal "GND6")
		(32 "In15.Cu" signal "IN6")
		(34 "In16.Cu" signal "GND7")
		(2 "B.Cu" signal "BOTTOM")
		(9 "F.Adhes" user "F.Adhesive")
		(11 "B.Adhes" user "B.Adhesive")
		(13 "F.Paste" user "Package Geometry/Pastemask Top")
		(15 "B.Paste" user "Package Geometry/Pastemask Bottom")
		(5 "F.SilkS" user "Ref Des/Silkscreen Top")
		(7 "B.SilkS" user "Ref Des/Silkscreen Bottom")
		(1 "F.Mask" user "Board Geometry/Soldermask Top")
		(3 "B.Mask" user "Board Geometry/Soldermask Bottom")
		(17 "Dwgs.User" user "User.Drawings")
		(19 "Cmts.User" user "User.Comments")
		(21 "Eco1.User" user "User.Eco1")
		(23 "Eco2.User" user "User.Eco2")
		(25 "Edge.Cuts" user "Board Geometry/Outline")
		(27 "Margin" user)
		(31 "F.CrtYd" user "Package Geometry/Place Bound Top")
		(29 "B.CrtYd" user "Package Geometry/Place Bound Bottom")
		(35 "F.Fab" user "Ref Des/Assembly Top")
		(33 "B.Fab" user "Ref Des/Assembly Bottom")
	)
	(footprint ""
		(layer "B.Cu")
		(at 270.645128 -244.08511 180)
		(property "Reference" "R380"
			(at 0 0 0)
			(layer "B.SilkS")
			(hide yes)
			(effects
				(font
					(size 1.27 1.27)
				)
				(justify mirror)
			)
		)
		(property "Value" ""
			(at 0 0 0)
			(layer "B.Fab")
			(effects
				(font
					(size 1.27 1.27)
				)
				(justify mirror)
			)
		)
		(duplicate_pad_numbers_are_jumpers no)
		(fp_line
			(start 0.7874 0.4064)
			(end 0.7874 -0.4064)
			(stroke
				(width 0.1524)
				(type default)
			)
			(layer "B.SilkS")
		)
		(fp_line
			(start 0.7874 -0.4064)
			(end -0.7874 -0.4064)
			(stroke
				(width 0.1524)
				(type default)
			)
			(layer "B.SilkS")
		)
		(fp_line
			(start -0.7874 0.4064)
			(end 0.7874 0.4064)
			(stroke
				(width 0.1524)
				(type default)
			)
			(layer "B.SilkS")
		)
		(fp_line
			(start -0.7874 -0.4064)
			(end -0.7874 0.4064)
			(stroke
				(width 0.1524)
				(type default)
			)
			(layer "B.SilkS")
		)
		(fp_line
			(start 0.67945 0.3048)
			(end 0.67945 -0.305054)
			(stroke
				(width 0.1)
				(type default)
			)
			(layer "B.Fab")
		)
		(fp_line
			(start 0.67945 -0.305054)
			(end 0.12065 -0.305054)
			(stroke
				(width 0.1)
				(type default)
			)
			(layer "B.Fab")
		)
		(fp_line
			(start 0.12065 0.3048)
			(end 0.67945 0.3048)
			(stroke
				(width 0.1)
				(type default)
			)
			(layer "B.Fab")
		)
		(fp_line
			(start 0.12065 0.2794)
			(end 0.12065 0.3048)
			(stroke
				(width 0.1)
				(type default)
			)
			(layer "B.Fab")
		)
		(fp_line
			(start 0.12065 -0.2794)
			(end -0.12065 -0.2794)
			(stroke
				(width 0.1)
				(type default)
			)
			(layer "B.Fab")
		)
		(fp_line
			(start 0.12065 -0.305054)
			(end 0.12065 -0.2794)
			(stroke
				(width 0.1)
				(type default)
			)
			(layer "B.Fab")
		)
		(fp_line
			(start -0.120396 0.3048)
			(end -0.120396 0.2794)
			(stroke
				(width 0.1)
				(type default)
			)
			(layer "B.Fab")
		)
		(fp_line
			(start -0.120396 0.2794)
			(end 0.12065 0.2794)
			(stroke
				(width 0.1)
				(type default)
			)
			(layer "B.Fab")
		)
		(fp_line
			(start -0.12065 -0.2794)
			(end -0.12065 -0.3048)
			(stroke
				(width 0.1)
				(type default)
			)
			(layer "B.Fab")
		)
		(fp_line
			(start -0.12065 -0.3048)
			(end -0.67945 -0.3048)
			(stroke
				(width 0.1)
				(type default)
			)
			(layer "B.Fab")
		)
		(fp_line
			(start -0.67945 0.3048)
			(end -0.120396 0.3048)
			(stroke
				(width 0.1)
				(type default)
			)
			(layer "B.Fab")
		)
		(fp_line
			(start -0.67945 -0.3048)
			(end -0.67945 0.3048)
			(stroke
				(width 0.1)
				(type default)
			)
			(layer "B.Fab")
		)
		(pad "1" smd circle
			(at 0.40005 0)
			(size 0 0)
			(layers "B.Cu" "B.Mask" "B.Paste")
			(net "M_F_CPU0_ALERT_N")
		)
		(pad "2" smd circle
			(at -0.40005 0)
			(size 0 0)
			(layers "B.Cu" "B.Mask" "B.Paste")
			(net "M_F_CPU0_ALERT_R_N")
		)
	)
	(footprint ""
		(layer "B.Cu")
		(at 154.577288 -8.68045 -90)
		(property "Reference" "R6069"
			(at 0 0 90)
			(layer "B.SilkS")
			(hide yes)
			(effects
				(font
					(size 1.27 1.27)
				)
				(justify mirror)
			)
		)
		(property "Value" ""
			(at 0 0 90)
			(layer "B.Fab")
			(effects
				(font
					(size 1.27 1.27)
				)
				(justify mirror)
			)
		)
		(duplicate_pad_numbers_are_jumpers no)
		(fp_line
			(start -0.7874 0.4064)
			(end 0.7874 0.4064)
			(stroke
				(width 0.1524)
				(type default)
			)
			(layer "B.SilkS")
		)
		(fp_line
			(start 0.7874 0.4064)
			(end 0.7874 -0.4064)
			(stroke
				(width 0.1524)
				(type default)
			)
			(layer "B.SilkS")
		)
		(fp_line
			(start -0.7874 -0.4064)
			(end -0.7874 0.4064)
			(stroke
				(width 0.1524)
				(type default)
			)
			(layer "B.SilkS")
		)
		(fp_line
			(start 0.7874 -0.4064)
			(end -0.7874 -0.4064)
			(stroke
				(width 0.1524)
				(type default)
			)
			(layer "B.SilkS")
		)
		(fp_line
			(start -0.67945 0.3048)
			(end -0.120396 0.3048)
			(stroke
				(width 0.1)
				(type default)
			)
			(layer "B.Fab")
		)
		(fp_line
			(start -0.120396 0.3048)
			(end -0.120396 0.2794)
			(stroke
				(width 0.1)
				(type default)
			)
			(layer "B.Fab")
		)
		(fp_line
			(start 0.12065 0.3048)
			(end 0.67945 0.3048)
			(stroke
				(width 0.1)
				(type default)
			)
			(layer "B.Fab")
		)
		(fp_line
			(start 0.67945 0.3048)
			(end 0.67945 -0.305054)
			(stroke
				(width 0.1)
				(type default)
			)
			(layer "B.Fab")
		)
		(fp_line
			(start -0.120396 0.2794)
			(end 0.12065 0.2794)
			(stroke
				(width 0.1)
				(type default)
			)
			(layer "B.Fab")
		)
		(fp_line
			(start 0.12065 0.2794)
			(end 0.12065 0.3048)
			(stroke
				(width 0.1)
				(type default)
			)
			(layer "B.Fab")
		)
		(fp_line
			(start -0.12065 -0.2794)
			(end -0.12065 -0.3048)
			(stroke
				(width 0.1)
				(type default)
			)
			(layer "B.Fab")
		)
		(fp_line
			(start 0.12065 -0.2794)
			(end -0.12065 -0.2794)
			(stroke
				(width 0.1)
				(type default)
			)
			(layer "B.Fab")
		)
		(fp_line
			(start -0.67945 -0.3048)
			(end -0.67945 0.3048)
			(stroke
				(width 0.1)
				(type default)
			)
			(layer "B.Fab")
		)
		(fp_line
			(start -0.12065 -0.3048)
			(end -0.67945 -0.3048)
			(stroke
				(width 0.1)
				(type default)
			)
			(layer "B.Fab")
		)
		(fp_line
			(start 0.12065 -0.305054)
			(end 0.12065 -0.2794)
			(stroke
				(width 0.1)
				(type default)
			)
			(layer "B.Fab")
		)
		(fp_line
			(start 0.67945 -0.305054)
			(end 0.12065 -0.305054)
			(stroke
				(width 0.1)
				(type default)
			)
			(layer "B.Fab")
		)
		(pad "1" smd rect
			(at 0.40005 0 270)
			(size 0.4572 0.508)
			(layers "B.Cu" "B.Mask" "B.Paste")
			(net "JTAG_SCM_TDI_R")
		)
		(pad "2" smd rect
			(at -0.40005 0 270)
			(size 0.4572 0.508)
			(layers "B.Cu" "B.Mask" "B.Paste")
			(net "JTAG_SCM_TDO")
		)
	)
)
